FILE_TYPE = MULTI_PHYS_TABLE;
PART 'SPRINGVILLE'
{===============================================================================================================================================================================================}
:PACK_TYPE | MATERIAL | PART_NUMBER     = EnvComp | PART_NUMBER  | JEDEC_TYPE        | DESCRIPTION                     | CLASS | COMPONENT_TYPE | HEIGHT     | LPID   | SPEED_URL | Status |RPL| AML | Bus_Unit | Days ;
{===============================================================================================================================================================================================}
'SM1'      | 'IC'     | 'G47144-004'(!) = 'YES;YES;YES;UNK;ok;VLD' | 'G47144-004' | 'QFN64_36_5ME'    | '(USE SYM_2)SPRINGVILLE GbE CONTROLLER,A2(142 SQ TH PAD)' | 'IC'  | 'LCC'          | '0.039 IN' | '2655' | 'http://speed.intel.com:8081/speed/module/pdm/item/pdm_item_detail_direct.asp?item_cde=G47144-004&item_rev=01&url_param=unused' | 'Approved' | 'NO' | '1' | 'LAD_SILICON' | '84' 
'SM1'      | 'EMPTY'  | 'G47144-004'(!) = 'YES;YES;YES;UNK;ok;VLD' | 'G47144-004' | 'QFN64_36_5ME'    | '(USE SYM_2)SPRINGVILLE GbE CONTROLLER,A2(142 SQ TH PAD)' | 'IO'  | 'LCC'          | '0.039 IN' | '2655' | 'http://speed.intel.com:8081/speed/module/pdm/item/pdm_item_detail_direct.asp?item_cde=G47144-004&item_rev=01&url_param=unused' | 'Approved' | 'NO' | '1' | 'LAD_SILICON' | '84' 
END_PART
END.
